# ZAIUS-LV_CARD-EVT1-X00-BOM-X01_20160825.xls — Summary (bom)
| PLATFORM SOURCING AND PSL COMPLIANCE |  |  |  |  |  |  |  |  |  |
| Platform Name: |  |  |  |  |  |  |  |  |  |
| REVISION HISTORY |  |  |  |  |  |  |  |  |  |
| BOM Revision: | ECR # | Revision Description | Originator | Date |  |  |  |  |  |
| Commodity Sourcing | # of components (X00 BOM) | % of Total | # of components (X01 BOM) | % of Total | # of components (X02 BOM) | % of Total | # of components (RTS) | % of Total | Risk Mitigation Plans in Place |
| Sole Source |  |  |  |  |  |  |  |  |  |
| Single Source |  |  |  |  |  |  |  |  |  |
| Multiple |  |  |  |  |  |  |  |  | NA |
| Total |  |  |  |  |  |  |  |  | NA |
|  |  | # of components | # of components aligned with Dell PSL* | % PSL alignment |  |  |  |  |  |
| Class 1 (Dell Managed) |  |  |  |  |  |  |  |  |  |
| Class 2 (ODM Managed to Dell PSL) |  |  |  |  |  |  |  |  |  |
| All other components(ODM Managed to ODM PSL) |  |  |  |  |  |  |  |  |  |
| *RFQ and/or Contract will list requirements for complying with Dell's PSL |  |  |  |  |  |  |  |  |  |
| Reference for quotation |  |  |  |  |  |  |  |  |  |
